(kicad_pcb
	(version 20260206)
	(generator "pcbnew")
	(generator_version "10.0")
	(general
		(thickness 1.6)
		(legacy_teardrops no)
	)
	(paper "A4")
	(title_block
		(title "netronome-mezz — pcbd0082-001_rev01_jul9_a.brd")
		(comment 1 "Open CloudServer (Microsoft) / footprints 648-658 of 714")
	)
	(layers
		(0 "F.Cu" signal "TOP")
		(4 "In1.Cu" signal "02_GND")
		(6 "In2.Cu" signal "03_SIG")
		(8 "In3.Cu" signal "04_SIG")
		(10 "In4.Cu" signal "05_GND")
		(12 "In5.Cu" signal "06_PWR1")
		(14 "In6.Cu" signal "07_SIG")
		(16 "In7.Cu" signal "08_SIG")
		(18 "In8.Cu" signal "09_GND")
		(2 "B.Cu" signal "BOTTOM")
		(9 "F.Adhes" user "F.Adhesive")
		(11 "B.Adhes" user "B.Adhesive")
		(13 "F.Paste" user "Package Geometry/Pastemask Top")
		(15 "B.Paste" user "Package Geometry/Pastemask Bottom")
		(5 "F.SilkS" user "Ref Des/Silkscreen Top")
		(7 "B.SilkS" user "Ref Des/Silkscreen Bottom")
		(1 "F.Mask" user "Board Geometry/Soldermask Top")
		(3 "B.Mask" user "Board Geometry/Soldermask Bottom")
		(17 "Dwgs.User" user "User.Drawings")
		(19 "Cmts.User" user "User.Comments")
		(21 "Eco1.User" user "User.Eco1")
		(23 "Eco2.User" user "User.Eco2")
		(25 "Edge.Cuts" user "Board Geometry/Outline")
		(27 "Margin" user)
		(31 "F.CrtYd" user "Package Geometry/Place Bound Top")
		(29 "B.CrtYd" user "Package Geometry/Place Bound Bottom")
		(35 "F.Fab" user "Ref Des/Assembly Top")
		(33 "B.Fab" user "Ref Des/Assembly Bottom")
		(45 "User.4" user "COMPVAL_TYPE_BOTTOM")
	)
	(footprint ""
		(layer "B.Cu")
		(at 63.236983 9.542018 180)
		(property "Reference" "C195"
			(at 0 0 0)
			(layer "B.SilkS")
			(hide yes)
			(effects
				(font
					(size 1.27 1.27)
				)
				(justify mirror)
			)
		)
		(property "Value" ""
			(at 0 0 0)
			(layer "B.Fab")
			(effects
				(font
					(size 1.27 1.27)
				)
				(justify mirror)
			)
		)
		(duplicate_pad_numbers_are_jumpers no)
		(fp_circle
			(center 0 0)
			(end -0.104648 0)
			(stroke
				(width 0.1016)
				(type default)
			)
			(fill no)
			(layer "B.SilkS")
		)
		(fp_poly
			(pts
				(xy 0.381 -0.889) (xy 0.381 0.889) (xy -0.381 0.889) (xy -0.381 -0.889)
			)
			(stroke
				(width 0)
				(type default)
			)
			(fill no)
			(layer "B.CrtYd")
		)
		(fp_line
			(start 0.508 1.016)
			(end 0.508 -1.016)
			(stroke
				(width 0.0254)
				(type default)
			)
			(layer "B.Fab")
		)
		(fp_line
			(start 0.508 -1.016)
			(end 0.254 -1.016)
			(stroke
				(width 0.0254)
				(type default)
			)
			(layer "B.Fab")
		)
		(fp_line
			(start 0.254 -1.016)
			(end -0.508 -1.016)
			(stroke
				(width 0.0254)
				(type default)
			)
			(layer "B.Fab")
		)
		(fp_line
			(start -0.508 1.016)
			(end 0.508 1.016)
			(stroke
				(width 0.0254)
				(type default)
			)
			(layer "B.Fab")
		)
		(fp_line
			(start -0.508 -1.016)
			(end -0.508 1.016)
			(stroke
				(width 0.0254)
				(type default)
			)
			(layer "B.Fab")
		)
		(pad "1" smd custom
			(at 0 -0.500126)
			(size 0.127 0.127)
			(layers "B.Cu" "B.Mask" "B.Paste")
			(net "DDR_VDDQ")
			(options
				(clearance outline)
				(anchor circle)
			)
			(primitives
				(gr_poly
					(pts
						(xy -0.1778 0.254) (xy 0.1778 0.254) (xy 0.254 0.1778) (xy 0.254 -0.1778) (xy 0.1778 -0.254) (xy -0.1778 -0.254)
						(xy -0.254 -0.1778) (xy -0.254 0.1778)
					)
					(width 0)
					(fill yes)
				)
			)
		)
		(pad "2" smd custom
			(at 0 0.500126)
			(size 0.127 0.127)
			(layers "B.Cu" "B.Mask" "B.Paste")
			(net "GND")
			(options
				(clearance outline)
				(anchor circle)
			)
			(primitives
				(gr_poly
					(pts
						(xy -0.1778 0.254) (xy 0.1778 0.254) (xy 0.254 0.1778) (xy 0.254 -0.1778) (xy 0.1778 -0.254) (xy -0.1778 -0.254)
						(xy -0.254 -0.1778) (xy -0.254 0.1778)
					)
					(width 0)
					(fill yes)
				)
			)
		)
	)
	(footprint ""
		(layer "B.Cu")
		(at 80.250995 25.813004)
		(property "Reference" "V3_A-WE"
			(at 0 0 0)
			(layer "B.SilkS")
			(hide yes)
			(effects
				(font
					(size 1.27 1.27)
				)
				(justify mirror)
			)
		)
		(property "Value" ""
			(at 0 0 0)
			(layer "B.Fab")
			(effects
				(font
					(size 1.27 1.27)
				)
				(justify mirror)
			)
		)
		(duplicate_pad_numbers_are_jumpers no)
		(pad "1" thru_hole circle
			(at 0 0 180)
			(size 0.4572 0.4572)
			(drill 0.20574)
			(layers "*.Cu" "*.Mask")
			(remove_unused_layers no)
			(net "DDR0_32A_WE_L")
			(clearance 0.1143)
			(thermal_gap 0.1143)
		)
	)
	(footprint ""
		(layer "B.Cu")
		(at 75.451005 1.899006)
		(property "Reference" "V_A-DQ00"
			(at 0 0 0)
			(layer "B.SilkS")
			(hide yes)
			(effects
				(font
					(size 1.27 1.27)
				)
				(justify mirror)
			)
		)
		(property "Value" ""
			(at 0 0 0)
			(layer "B.Fab")
			(effects
				(font
					(size 1.27 1.27)
				)
				(justify mirror)
			)
		)
		(duplicate_pad_numbers_are_jumpers no)
		(pad "1" thru_hole circle
			(at 0 0 180)
			(size 0.4572 0.4572)
			(drill 0.20574)
			(layers "*.Cu" "*.Mask")
			(remove_unused_layers no)
			(net "DDR0_32A_DQ0")
			(clearance 0.1143)
			(thermal_gap 0.1143)
		)
	)
	(footprint ""
		(layer "B.Cu")
		(at 47.736887 12.04214 -90)
		(property "Reference" "C93"
			(at 0 0 90)
			(layer "B.SilkS")
			(hide yes)
			(effects
				(font
					(size 1.27 1.27)
				)
				(justify mirror)
			)
		)
		(property "Value" ""
			(at 0 0 90)
			(layer "B.Fab")
			(effects
				(font
					(size 1.27 1.27)
				)
				(justify mirror)
			)
		)
		(duplicate_pad_numbers_are_jumpers no)
		(fp_circle
			(center 0 0)
			(end 0 -0.104648)
			(stroke
				(width 0.1016)
				(type default)
			)
			(fill no)
			(layer "B.SilkS")
		)
		(fp_poly
			(pts
				(xy 0.381 -0.889) (xy 0.381 0.889) (xy -0.381 0.889) (xy -0.381 -0.889)
			)
			(stroke
				(width 0)
				(type default)
			)
			(fill no)
			(layer "B.CrtYd")
		)
		(fp_line
			(start -0.508 1.016)
			(end 0.508 1.016)
			(stroke
				(width 0.0254)
				(type default)
			)
			(layer "B.Fab")
		)
		(fp_line
			(start 0.508 1.016)
			(end 0.508 -1.016)
			(stroke
				(width 0.0254)
				(type default)
			)
			(layer "B.Fab")
		)
		(fp_line
			(start -0.508 -1.016)
			(end -0.508 1.016)
			(stroke
				(width 0.0254)
				(type default)
			)
			(layer "B.Fab")
		)
		(fp_line
			(start 0.254 -1.016)
			(end -0.508 -1.016)
			(stroke
				(width 0.0254)
				(type default)
			)
			(layer "B.Fab")
		)
		(fp_line
			(start 0.508 -1.016)
			(end 0.254 -1.016)
			(stroke
				(width 0.0254)
				(type default)
			)
			(layer "B.Fab")
		)
		(pad "1" smd custom
			(at 0 -0.500126 90)
			(size 0.127 0.127)
			(layers "B.Cu" "B.Mask" "B.Paste")
			(net "VDDA_SERDES")
			(options
				(clearance outline)
				(anchor circle)
			)
			(primitives
				(gr_poly
					(pts
						(xy -0.1778 0.254) (xy 0.1778 0.254) (xy 0.254 0.1778) (xy 0.254 -0.1778) (xy 0.1778 -0.254) (xy -0.1778 -0.254)
						(xy -0.254 -0.1778) (xy -0.254 0.1778)
					)
					(width 0)
					(fill yes)
				)
			)
		)
		(pad "2" smd custom
			(at 0 0.500126 90)
			(size 0.127 0.127)
			(layers "B.Cu" "B.Mask" "B.Paste")
			(net "GND")
			(options
				(clearance outline)
				(anchor circle)
			)
			(primitives
				(gr_poly
					(pts
						(xy -0.1778 0.254) (xy 0.1778 0.254) (xy 0.254 0.1778) (xy 0.254 -0.1778) (xy 0.1778 -0.254) (xy -0.1778 -0.254)
						(xy -0.254 -0.1778) (xy -0.254 0.1778)
					)
					(width 0)
					(fill yes)
				)
			)
		)
	)
	(footprint ""
		(layer "B.Cu")
		(at 74.651006 2.699004)
		(property "Reference" "V_A-DQ05"
			(at 0 0 0)
			(layer "B.SilkS")
			(hide yes)
			(effects
				(font
					(size 1.27 1.27)
				)
				(justify mirror)
			)
		)
		(property "Value" ""
			(at 0 0 0)
			(layer "B.Fab")
			(effects
				(font
					(size 1.27 1.27)
				)
				(justify mirror)
			)
		)
		(duplicate_pad_numbers_are_jumpers no)
		(pad "1" thru_hole circle
			(at 0 0 180)
			(size 0.4572 0.4572)
			(drill 0.20574)
			(layers "*.Cu" "*.Mask")
			(remove_unused_layers no)
			(net "DDR0_32A_DQ5")
			(clearance 0.1143)
			(thermal_gap 0.1143)
		)
	)
	(footprint ""
		(layer "B.Cu")
		(at 57.277 41.91)
		(property "Reference" "C18"
			(at 0.60833 3.429 270)
			(unlocked yes)
			(layer "B.SilkS")
			(effects
				(font
					(size 0.7874 0.5842)
					(thickness 0.127)
				)
				(justify left mirror)
			)
		)
		(property "Value" "22UF"
			(at 0.148158 1.7526 270)
			(unlocked yes)
			(layer "B.Fab")
			(hide yes)
			(effects
				(font
					(size 1.27 0.9652)
					(thickness 0.000001)
				)
				(justify left mirror)
			)
		)
		(property "Device Type" "CAPC0063"
			(at 0.148158 1.7526 270)
			(unlocked yes)
			(layer "B.Fab")
			(hide yes)
			(effects
				(font
					(size 1.27 0.9652)
					(thickness 0.000001)
				)
				(justify left mirror)
			)
		)
		(duplicate_pad_numbers_are_jumpers no)
		(fp_circle
			(center 0 0)
			(end 0.127 0)
			(stroke
				(width 0.2032)
				(type default)
			)
			(fill no)
			(layer "B.SilkS")
		)
		(fp_poly
			(pts
				(xy -0.7874 -1.6637) (xy 0.7874 -1.6637) (xy 0.7874 1.6637) (xy -0.7874 1.6637)
			)
			(stroke
				(width 0)
				(type default)
			)
			(fill no)
			(layer "B.CrtYd")
		)
		(fp_line
			(start -0.4064 -0.7874)
			(end -0.4064 0.8128)
			(stroke
				(width 0.0254)
				(type default)
			)
			(layer "B.Fab")
		)
		(fp_line
			(start -0.4064 0.8128)
			(end 0.4064 0.8128)
			(stroke
				(width 0.0254)
				(type default)
			)
			(layer "B.Fab")
		)
		(fp_line
			(start 0.4064 -0.7874)
			(end -0.4064 -0.7874)
			(stroke
				(width 0.0254)
				(type default)
			)
			(layer "B.Fab")
		)
		(fp_line
			(start 0.4064 0.8128)
			(end 0.4064 -0.7874)
			(stroke
				(width 0.0254)
				(type default)
			)
			(layer "B.Fab")
		)
		(pad "1" smd rect
			(at 0 -0.8001 180)
			(size 0.8636 0.9652)
			(layers "B.Cu" "B.Mask" "B.Paste")
			(net "VDD_CORE")
		)
		(pad "2" smd rect
			(at 0 0.8001 180)
			(size 0.8636 0.9652)
			(layers "B.Cu" "B.Mask" "B.Paste")
			(net "GND")
		)
		(zone
			(layer "B.Cu")
			(hatch none 0.5)
			(connect_pads
				(clearance 0)
			)
			(min_thickness 0.25)
			(keepout
				(tracks not_allowed)
				(vias allowed)
				(pads allowed)
				(copperpour not_allowed)
				(footprints allowed)
			)
			(placement
				(enabled no)
				(sheetname "")
			)
			(fill
				(thermal_gap 0.5)
				(thermal_bridge_width 0.5)
				(island_removal_mode 0)
			)
			(polygon
				(pts
					(xy 57.3405 41.656) (xy 57.2135 41.656) (xy 57.2135 42.164) (xy 57.3405 42.164)
				)
			)
		)
	)
	(footprint ""
		(layer "B.Cu")
		(at 50.237009 9.542018)
		(property "Reference" "C103"
			(at 0 0 0)
			(layer "B.SilkS")
			(hide yes)
			(effects
				(font
					(size 1.27 1.27)
				)
				(justify mirror)
			)
		)
		(property "Value" ""
			(at 0 0 0)
			(layer "B.Fab")
			(effects
				(font
					(size 1.27 1.27)
				)
				(justify mirror)
			)
		)
		(duplicate_pad_numbers_are_jumpers no)
		(fp_circle
			(center 0 0)
			(end 0.104648 0)
			(stroke
				(width 0.1016)
				(type default)
			)
			(fill no)
			(layer "B.SilkS")
		)
		(fp_poly
			(pts
				(xy 0.381 -0.889) (xy 0.381 0.889) (xy -0.381 0.889) (xy -0.381 -0.889)
			)
			(stroke
				(width 0)
				(type default)
			)
			(fill no)
			(layer "B.CrtYd")
		)
		(fp_line
			(start -0.508 -1.016)
			(end -0.508 1.016)
			(stroke
				(width 0.0254)
				(type default)
			)
			(layer "B.Fab")
		)
		(fp_line
			(start -0.508 1.016)
			(end 0.508 1.016)
			(stroke
				(width 0.0254)
				(type default)
			)
			(layer "B.Fab")
		)
		(fp_line
			(start 0.254 -1.016)
			(end -0.508 -1.016)
			(stroke
				(width 0.0254)
				(type default)
			)
			(layer "B.Fab")
		)
		(fp_line
			(start 0.508 -1.016)
			(end 0.254 -1.016)
			(stroke
				(width 0.0254)
				(type default)
			)
			(layer "B.Fab")
		)
		(fp_line
			(start 0.508 1.016)
			(end 0.508 -1.016)
			(stroke
				(width 0.0254)
				(type default)
			)
			(layer "B.Fab")
		)
		(pad "1" smd custom
			(at 0 -0.500126 180)
			(size 0.127 0.127)
			(layers "B.Cu" "B.Mask" "B.Paste")
			(net "VDDAH_SERDES")
			(options
				(clearance outline)
				(anchor circle)
			)
			(primitives
				(gr_poly
					(pts
						(xy -0.1778 0.254) (xy 0.1778 0.254) (xy 0.254 0.1778) (xy 0.254 -0.1778) (xy 0.1778 -0.254) (xy -0.1778 -0.254)
						(xy -0.254 -0.1778) (xy -0.254 0.1778)
					)
					(width 0)
					(fill yes)
				)
			)
		)
		(pad "2" smd custom
			(at 0 0.500126 180)
			(size 0.127 0.127)
			(layers "B.Cu" "B.Mask" "B.Paste")
			(net "GND")
			(options
				(clearance outline)
				(anchor circle)
			)
			(primitives
				(gr_poly
					(pts
						(xy -0.1778 0.254) (xy 0.1778 0.254) (xy 0.254 0.1778) (xy 0.254 -0.1778) (xy 0.1778 -0.254) (xy -0.1778 -0.254)
						(xy -0.254 -0.1778) (xy -0.254 0.1778)
					)
					(width 0)
					(fill yes)
				)
			)
		)
	)
	(footprint ""
		(layer "B.Cu")
		(at 23.749 11.303 90)
		(property "Reference" "R403"
			(at 0 0 90)
			(layer "B.SilkS")
			(hide yes)
			(effects
				(font
					(size 1.27 1.27)
				)
				(justify mirror)
			)
		)
		(property "Value" "4.75K"
			(at 0.148158 1.3462 0)
			(unlocked yes)
			(layer "B.Fab")
			(hide yes)
			(effects
				(font
					(size 1.27 0.9652)
					(thickness 0.000001)
				)
				(justify left mirror)
			)
		)
		(property "Device Type" "REST4024"
			(at 0.148158 1.3462 0)
			(unlocked yes)
			(layer "B.Fab")
			(hide yes)
			(effects
				(font
					(size 1.27 0.9652)
					(thickness 0.000001)
				)
				(justify left mirror)
			)
		)
		(duplicate_pad_numbers_are_jumpers no)
		(fp_poly
			(pts
				(xy -0.635 1.0668) (xy -0.635 -1.0668) (xy 0.635 -1.0668) (xy 0.635 1.0668)
			)
			(stroke
				(width 0)
				(type default)
			)
			(fill no)
			(layer "B.CrtYd")
		)
		(fp_line
			(start 0.254 -0.508)
			(end -0.254 -0.508)
			(stroke
				(width 0.0254)
				(type default)
			)
			(layer "B.Fab")
		)
		(fp_line
			(start -0.254 -0.508)
			(end -0.254 0.508)
			(stroke
				(width 0.0254)
				(type default)
			)
			(layer "B.Fab")
		)
		(fp_line
			(start 0.254 0.508)
			(end 0.254 -0.508)
			(stroke
				(width 0.0254)
				(type default)
			)
			(layer "B.Fab")
		)
		(fp_line
			(start -0.254 0.508)
			(end 0.254 0.508)
			(stroke
				(width 0.0254)
				(type default)
			)
			(layer "B.Fab")
		)
		(pad "1" smd rect
			(at 0 -0.4191 270)
			(size 0.508 0.5334)
			(layers "B.Cu" "B.Mask" "B.Paste")
			(net "VDD_3.3V")
		)
		(pad "2" smd rect
			(at 0 0.4191 270)
			(size 0.508 0.5334)
			(layers "B.Cu" "B.Mask" "B.Paste")
			(net "NFP_JTAG_ARM_TDI")
		)
		(zone
			(layer "B.Cu")
			(hatch none 0.5)
			(connect_pads
				(clearance 0)
			)
			(min_thickness 0.25)
			(keepout
				(tracks not_allowed)
				(vias allowed)
				(pads allowed)
				(copperpour not_allowed)
				(footprints allowed)
			)
			(placement
				(enabled no)
				(sheetname "")
			)
			(fill
				(thermal_gap 0.5)
				(thermal_bridge_width 0.5)
				(island_removal_mode 0)
			)
			(polygon
				(pts
					(xy 23.7236 11.3284) (xy 23.7744 11.3284) (xy 23.7744 11.2776) (xy 23.7236 11.2776)
				)
			)
		)
	)
	(footprint ""
		(layer "B.Cu")
		(at 75.451005 18.255996)
		(property "Reference" "V_A-DQ18"
			(at 0 0 0)
			(layer "B.SilkS")
			(hide yes)
			(effects
				(font
					(size 1.27 1.27)
				)
				(justify mirror)
			)
		)
		(property "Value" ""
			(at 0 0 0)
			(layer "B.Fab")
			(effects
				(font
					(size 1.27 1.27)
				)
				(justify mirror)
			)
		)
		(duplicate_pad_numbers_are_jumpers no)
		(pad "1" thru_hole circle
			(at 0 0 180)
			(size 0.4572 0.4572)
			(drill 0.20574)
			(layers "*.Cu" "*.Mask")
			(remove_unused_layers no)
			(net "DDR0_32A_DQ18")
			(clearance 0.1143)
			(thermal_gap 0.1143)
		)
	)
	(footprint ""
		(layer "B.Cu")
		(at 60.736988 17.042003 -90)
		(property "Reference" "C29"
			(at 0 0 90)
			(layer "B.SilkS")
			(hide yes)
			(effects
				(font
					(size 1.27 1.27)
				)
				(justify mirror)
			)
		)
		(property "Value" ""
			(at 0 0 90)
			(layer "B.Fab")
			(effects
				(font
					(size 1.27 1.27)
				)
				(justify mirror)
			)
		)
		(duplicate_pad_numbers_are_jumpers no)
		(fp_circle
			(center 0 0)
			(end 0 -0.104648)
			(stroke
				(width 0.1016)
				(type default)
			)
			(fill no)
			(layer "B.SilkS")
		)
		(fp_poly
			(pts
				(xy 0.381 -0.889) (xy 0.381 0.889) (xy -0.381 0.889) (xy -0.381 -0.889)
			)
			(stroke
				(width 0)
				(type default)
			)
			(fill no)
			(layer "B.CrtYd")
		)
		(fp_line
			(start -0.508 1.016)
			(end 0.508 1.016)
			(stroke
				(width 0.0254)
				(type default)
			)
			(layer "B.Fab")
		)
		(fp_line
			(start 0.508 1.016)
			(end 0.508 -1.016)
			(stroke
				(width 0.0254)
				(type default)
			)
			(layer "B.Fab")
		)
		(fp_line
			(start -0.508 -1.016)
			(end -0.508 1.016)
			(stroke
				(width 0.0254)
				(type default)
			)
			(layer "B.Fab")
		)
		(fp_line
			(start 0.254 -1.016)
			(end -0.508 -1.016)
			(stroke
				(width 0.0254)
				(type default)
			)
			(layer "B.Fab")
		)
		(fp_line
			(start 0.508 -1.016)
			(end 0.254 -1.016)
			(stroke
				(width 0.0254)
				(type default)
			)
			(layer "B.Fab")
		)
		(pad "1" smd custom
			(at 0 -0.500126 90)
			(size 0.127 0.127)
			(layers "B.Cu" "B.Mask" "B.Paste")
			(net "VDDA_PLL")
			(options
				(clearance outline)
				(anchor circle)
			)
			(primitives
				(gr_poly
					(pts
						(xy -0.1778 0.254) (xy 0.1778 0.254) (xy 0.254 0.1778) (xy 0.254 -0.1778) (xy 0.1778 -0.254) (xy -0.1778 -0.254)
						(xy -0.254 -0.1778) (xy -0.254 0.1778)
					)
					(width 0)
					(fill yes)
				)
			)
		)
		(pad "2" smd custom
			(at 0 0.500126 90)
			(size 0.127 0.127)
			(layers "B.Cu" "B.Mask" "B.Paste")
			(net "GND")
			(options
				(clearance outline)
				(anchor circle)
			)
			(primitives
				(gr_poly
					(pts
						(xy -0.1778 0.254) (xy 0.1778 0.254) (xy 0.254 0.1778) (xy 0.254 -0.1778) (xy 0.1778 -0.254) (xy -0.1778 -0.254)
						(xy -0.254 -0.1778) (xy -0.254 0.1778)
					)
					(width 0)
					(fill yes)
				)
			)
		)
	)
	(footprint ""
		(layer "B.Cu")
		(at 29.845 22.225 180)
		(property "Reference" "R52"
			(at 0 0 0)
			(layer "B.SilkS")
			(hide yes)
			(effects
				(font
					(size 1.27 1.27)
				)
				(justify mirror)
			)
		)
		(property "Value" "4.75K"
			(at 0.148158 1.3462 90)
			(unlocked yes)
			(layer "B.Fab")
			(hide yes)
			(effects
				(font
					(size 1.27 0.9652)
					(thickness 0.000001)
				)
				(justify left mirror)
			)
		)
		(property "Device Type" "REST4024"
			(at 0.148158 1.3462 90)
			(unlocked yes)
			(layer "B.Fab")
			(hide yes)
			(effects
				(font
					(size 1.27 0.9652)
					(thickness 0.000001)
				)
				(justify left mirror)
			)
		)
		(duplicate_pad_numbers_are_jumpers no)
		(fp_poly
			(pts
				(xy -0.635 1.0668) (xy -0.635 -1.0668) (xy 0.635 -1.0668) (xy 0.635 1.0668)
			)
			(stroke
				(width 0)
				(type default)
			)
			(fill no)
			(layer "B.CrtYd")
		)
		(fp_line
			(start 0.254 0.508)
			(end 0.254 -0.508)
			(stroke
				(width 0.0254)
				(type default)
			)
			(layer "B.Fab")
		)
		(fp_line
			(start 0.254 -0.508)
			(end -0.254 -0.508)
			(stroke
				(width 0.0254)
				(type default)
			)
			(layer "B.Fab")
		)
		(fp_line
			(start -0.254 0.508)
			(end 0.254 0.508)
			(stroke
				(width 0.0254)
				(type default)
			)
			(layer "B.Fab")
		)
		(fp_line
			(start -0.254 -0.508)
			(end -0.254 0.508)
			(stroke
				(width 0.0254)
				(type default)
			)
			(layer "B.Fab")
		)
		(pad "1" smd rect
			(at 0 -0.4191)
			(size 0.508 0.5334)
			(layers "B.Cu" "B.Mask" "B.Paste")
			(net "EXT_3.3V")
		)
		(pad "2" smd rect
			(at 0 0.4191)
			(size 0.508 0.5334)
			(layers "B.Cu" "B.Mask" "B.Paste")
			(net "CPLD_VERSION_1")
		)
		(zone
			(layer "B.Cu")
			(hatch none 0.5)
			(connect_pads
				(clearance 0)
			)
			(min_thickness 0.25)
			(keepout
				(tracks not_allowed)
				(vias allowed)
				(pads allowed)
				(copperpour not_allowed)
				(footprints allowed)
			)
			(placement
				(enabled no)
				(sheetname "")
			)
			(fill
				(thermal_gap 0.5)
				(thermal_bridge_width 0.5)
				(island_removal_mode 0)
			)
			(polygon
				(pts
					(xy 29.8704 22.2504) (xy 29.8704 22.1996) (xy 29.8196 22.1996) (xy 29.8196 22.2504)
				)
			)
		)
	)
)
